# BASEBOARD_FAB2 (Tioga Pass) — schematic netlist excerpt (pin names and nets, part order shuffled) for the footprints in the layout excerpt that follows; sources: Cadence DE-HDL packaged netlist, KiCad conversion of Wiwynn_Tioga_Pass_MB.brd

R3P59  RES  0.0 5% CHIP  pkg 0402  page 92 : A = H_CPU0_CATERR_G_N ; B = H_CPU_CATERR_G_N
C2R9  CAP  0.22UF 16V 10% X7R  pkg 0402  page 106 : A = P3E_CPU0_PE3_OCP_TXN<7> ; B = P3E_OCP_CPU0_PE3_C_TXN<7>
R1M18  RES  0.0 5% CHIP  pkg 0402  page 186 : A = RMII_BMC_OCP_RXER_R ; B = RMII_BMC_OCP_RXER

(kicad_pcb
	(version 20260206)
	(generator "pcbnew")
	(generator_version "10.0")
	(general
		(thickness 1.6)
		(legacy_teardrops no)
	)
	(paper "A4")
	(title_block
		(title "Wiwynn_Tioga_Pass_MB.brd")
		(comment 1 "Tioga Pass / footprints 3255-3257 of 4770")
	)
	(layers
		(0 "F.Cu" signal "TOP")
		(4 "In1.Cu" signal "L2GND")
		(6 "In2.Cu" signal "L3")
		(8 "In3.Cu" signal "L4GND")
		(10 "In4.Cu" signal "L5")
		(12 "In5.Cu" signal "L6GND")
		(14 "In6.Cu" signal "L7VCC")
		(16 "In7.Cu" signal "L8VCC")
		(18 "In8.Cu" signal "L9GND")
		(20 "In9.Cu" signal "L10")
		(22 "In10.Cu" signal "L11GND")
		(24 "In11.Cu" signal "L12")
		(26 "In12.Cu" signal "L13GND")
		(2 "B.Cu" signal "BOTTOM")
		(9 "F.Adhes" user "F.Adhesive")
		(11 "B.Adhes" user "B.Adhesive")
		(13 "F.Paste" user "Package Geometry/Pastemask Top")
		(15 "B.Paste" user "Package Geometry/Pastemask Bottom")
		(5 "F.SilkS" user "Ref Des/Silkscreen Top")
		(7 "B.SilkS" user "Ref Des/Silkscreen Bottom")
		(1 "F.Mask" user "Board Geometry/Soldermask Top")
		(3 "B.Mask" user "Board Geometry/Soldermask Bottom")
		(17 "Dwgs.User" user "User.Drawings")
		(19 "Cmts.User" user "User.Comments")
		(21 "Eco1.User" user "User.Eco1")
		(23 "Eco2.User" user "User.Eco2")
		(25 "Edge.Cuts" user "Board Geometry/Outline")
		(27 "Margin" user)
		(31 "F.CrtYd" user "Package Geometry/Place Bound Top")
		(29 "B.CrtYd" user "Package Geometry/Place Bound Bottom")
		(35 "F.Fab" user "Ref Des/Assembly Top")
		(33 "B.Fab" user "Ref Des/Assembly Bottom")
	)
	(footprint ""
		(layer "B.Cu")
		(at 373.6975 -56.769 -90)
		(property "Reference" "R3P59"
			(at 0 0 90)
			(layer "B.SilkS")
			(hide yes)
			(effects
				(font
					(size 1.27 1.27)
				)
				(justify mirror)
			)
		)
		(property "Value" ""
			(at 0 0 90)
			(layer "B.Fab")
			(effects
				(font
					(size 1.27 1.27)
				)
				(justify mirror)
			)
		)
		(duplicate_pad_numbers_are_jumpers no)
		(fp_poly
			(pts
				(xy 0.2794 -0.1016) (xy -0.2794 -0.1016) (xy -0.2794 0.9906) (xy 0.2794 0.9906)
			)
			(stroke
				(width 0)
				(type default)
			)
			(fill no)
			(layer "B.CrtYd")
		)
		(fp_line
			(start -0.2794 0.9906)
			(end -0.2794 -0.1016)
			(stroke
				(width 0.1)
				(type default)
			)
			(layer "B.Fab")
		)
		(fp_line
			(start 0.2794 0.9906)
			(end -0.2794 0.9906)
			(stroke
				(width 0.1)
				(type default)
			)
			(layer "B.Fab")
		)
		(fp_line
			(start -0.2794 -0.1016)
			(end 0.2794 -0.1016)
			(stroke
				(width 0.1)
				(type default)
			)
			(layer "B.Fab")
		)
		(fp_line
			(start 0.2794 -0.1016)
			(end 0.2794 0.9906)
			(stroke
				(width 0.1)
				(type default)
			)
			(layer "B.Fab")
		)
		(pad "1" smd rect
			(at 0 0 90)
			(size 0.508 0.508)
			(layers "B.Cu" "B.Mask" "B.Paste")
			(net "H_CPU0_CATERR_G_N")
		)
		(pad "2" smd rect
			(at 0 0.889 90)
			(size 0.508 0.508)
			(layers "B.Cu" "B.Mask" "B.Paste")
			(net "H_CPU_CATERR_G_N")
		)
		(zone
			(layer "B.Cu")
			(hatch none 0.5)
			(connect_pads
				(clearance 0)
			)
			(min_thickness 0.25)
			(keepout
				(tracks not_allowed)
				(vias allowed)
				(pads allowed)
				(copperpour not_allowed)
				(footprints allowed)
			)
			(placement
				(enabled no)
				(sheetname "")
			)
			(fill
				(thermal_gap 0.5)
				(thermal_bridge_width 0.5)
				(island_removal_mode 0)
			)
			(polygon
				(pts
					(xy 373.0625 -56.515) (xy 373.0625 -57.023) (xy 373.4435 -57.023) (xy 373.4435 -56.515)
				)
			)
		)
		(zone
			(layer "B.Cu")
			(hatch none 0.5)
			(connect_pads
				(clearance 0)
			)
			(min_thickness 0.25)
			(keepout
				(tracks allowed)
				(vias not_allowed)
				(pads allowed)
				(copperpour not_allowed)
				(footprints allowed)
			)
			(placement
				(enabled no)
				(sheetname "")
			)
			(fill
				(thermal_gap 0.5)
				(thermal_bridge_width 0.5)
				(island_removal_mode 0)
			)
			(polygon
				(pts
					(xy 373.4435 -56.515) (xy 373.4435 -57.023) (xy 373.0625 -57.023) (xy 373.0625 -56.515)
				)
			)
		)
	)
	(footprint ""
		(layer "B.Cu")
		(at 441.3504 -52.2986)
		(property "Reference" "C2R9"
			(at 0 0 0)
			(layer "B.SilkS")
			(hide yes)
			(effects
				(font
					(size 1.27 1.27)
				)
				(justify mirror)
			)
		)
		(property "Value" ""
			(at 0 0 0)
			(layer "B.Fab")
			(effects
				(font
					(size 1.27 1.27)
				)
				(justify mirror)
			)
		)
		(duplicate_pad_numbers_are_jumpers no)
		(fp_poly
			(pts
				(xy -0.3048 -0.1016) (xy -0.3048 0.9906) (xy 0.3048 0.9906) (xy 0.3048 -0.1016)
			)
			(stroke
				(width 0)
				(type default)
			)
			(fill no)
			(layer "B.CrtYd")
		)
		(fp_line
			(start -0.3048 -0.1016)
			(end 0.3048 -0.1016)
			(stroke
				(width 0.1)
				(type default)
			)
			(layer "B.Fab")
		)
		(fp_line
			(start -0.3048 0.9906)
			(end -0.3048 -0.1016)
			(stroke
				(width 0.1)
				(type default)
			)
			(layer "B.Fab")
		)
		(fp_line
			(start 0.3048 -0.1016)
			(end 0.3048 0.9906)
			(stroke
				(width 0.1)
				(type default)
			)
			(layer "B.Fab")
		)
		(fp_line
			(start 0.3048 0.9906)
			(end -0.3048 0.9906)
			(stroke
				(width 0.1)
				(type default)
			)
			(layer "B.Fab")
		)
		(pad "1" smd rect
			(at 0 0 180)
			(size 0.508 0.508)
			(layers "B.Cu" "B.Mask" "B.Paste")
			(net "P3E_CPU0_PE3_OCP_TXN<7>")
		)
		(pad "2" smd rect
			(at 0 0.889 180)
			(size 0.508 0.508)
			(layers "B.Cu" "B.Mask" "B.Paste")
			(net "P3E_OCP_CPU0_PE3_C_TXN<7>")
		)
		(zone
			(layer "B.Cu")
			(hatch none 0.5)
			(connect_pads
				(clearance 0)
			)
			(min_thickness 0.25)
			(keepout
				(tracks allowed)
				(vias not_allowed)
				(pads allowed)
				(copperpour not_allowed)
				(footprints allowed)
			)
			(placement
				(enabled no)
				(sheetname "")
			)
			(fill
				(thermal_gap 0.5)
				(thermal_bridge_width 0.5)
				(island_removal_mode 0)
			)
			(polygon
				(pts
					(xy 441.6044 -52.0446) (xy 441.0964 -52.0446) (xy 441.0964 -51.6636) (xy 441.6044 -51.6636)
				)
			)
		)
		(zone
			(layer "B.Cu")
			(hatch none 0.5)
			(connect_pads
				(clearance 0)
			)
			(min_thickness 0.25)
			(keepout
				(tracks not_allowed)
				(vias allowed)
				(pads allowed)
				(copperpour not_allowed)
				(footprints allowed)
			)
			(placement
				(enabled no)
				(sheetname "")
			)
			(fill
				(thermal_gap 0.5)
				(thermal_bridge_width 0.5)
				(island_removal_mode 0)
			)
			(polygon
				(pts
					(xy 441.6044 -51.6636) (xy 441.0964 -51.6636) (xy 441.0964 -52.0446) (xy 441.6044 -52.0446)
				)
			)
		)
	)
	(footprint ""
		(layer "B.Cu")
		(at 472.059 -112.141 -90)
		(property "Reference" "R1M18"
			(at 0 0 90)
			(layer "B.SilkS")
			(hide yes)
			(effects
				(font
					(size 1.27 1.27)
				)
				(justify mirror)
			)
		)
		(property "Value" ""
			(at 0 0 90)
			(layer "B.Fab")
			(effects
				(font
					(size 1.27 1.27)
				)
				(justify mirror)
			)
		)
		(duplicate_pad_numbers_are_jumpers no)
		(fp_poly
			(pts
				(xy 0.2794 -0.1016) (xy -0.2794 -0.1016) (xy -0.2794 0.9906) (xy 0.2794 0.9906)
			)
			(stroke
				(width 0)
				(type default)
			)
			(fill no)
			(layer "B.CrtYd")
		)
		(fp_line
			(start -0.2794 0.9906)
			(end -0.2794 -0.1016)
			(stroke
				(width 0.1)
				(type default)
			)
			(layer "B.Fab")
		)
		(fp_line
			(start 0.2794 0.9906)
			(end -0.2794 0.9906)
			(stroke
				(width 0.1)
				(type default)
			)
			(layer "B.Fab")
		)
		(fp_line
			(start -0.2794 -0.1016)
			(end 0.2794 -0.1016)
			(stroke
				(width 0.1)
				(type default)
			)
			(layer "B.Fab")
		)
		(fp_line
			(start 0.2794 -0.1016)
			(end 0.2794 0.9906)
			(stroke
				(width 0.1)
				(type default)
			)
			(layer "B.Fab")
		)
		(pad "1" smd rect
			(at 0 0 90)
			(size 0.508 0.508)
			(layers "B.Cu" "B.Mask" "B.Paste")
			(net "RMII_BMC_OCP_RXER_R")
		)
		(pad "2" smd rect
			(at 0 0.889 90)
			(size 0.508 0.508)
			(layers "B.Cu" "B.Mask" "B.Paste")
			(net "RMII_BMC_OCP_RXER")
		)
		(zone
			(layer "B.Cu")
			(hatch none 0.5)
			(connect_pads
				(clearance 0)
			)
			(min_thickness 0.25)
			(keepout
				(tracks not_allowed)
				(vias allowed)
				(pads allowed)
				(copperpour not_allowed)
				(footprints allowed)
			)
			(placement
				(enabled no)
				(sheetname "")
			)
			(fill
				(thermal_gap 0.5)
				(thermal_bridge_width 0.5)
				(island_removal_mode 0)
			)
			(polygon
				(pts
					(xy 471.424 -111.887) (xy 471.424 -112.395) (xy 471.805 -112.395) (xy 471.805 -111.887)
				)
			)
		)
		(zone
			(layer "B.Cu")
			(hatch none 0.5)
			(connect_pads
				(clearance 0)
			)
			(min_thickness 0.25)
			(keepout
				(tracks allowed)
				(vias not_allowed)
				(pads allowed)
				(copperpour not_allowed)
				(footprints allowed)
			)
			(placement
				(enabled no)
				(sheetname "")
			)
			(fill
				(thermal_gap 0.5)
				(thermal_bridge_width 0.5)
				(island_removal_mode 0)
			)
			(polygon
				(pts
					(xy 471.805 -111.887) (xy 471.805 -112.395) (xy 471.424 -112.395) (xy 471.424 -111.887)
				)
			)
		)
	)
)
